FILE_TYPE = CONNECTIVITY;
{Allegro Design Entry HDL 16.6-p007 (v16-6-112F) 10/10/2012}
"PAGE_NUMBER" = 242;
0"NC";
1"GND\g";
2"GND\g";
3"PVDDQ_ABC\g";
4"GND\g";
5"PVDDQ_DEF\g";
6"PVDDQ_ABC\g";
7"GND\g";
8"PVDDQ_DEF\g";
9"GND\g";
10"PVDDQ_DEF\g";
11"GND\g";
12"PVDDQ_ABC\g";
%"GND"
"1","(-7400,1100)","0","mstr_symbols","I1";
;
CDS_LIB"mstr_symbols"
SIZE"1B"
BOM_COST"PROC_VRD_VCCIN_CPU0"
ROOM"VDDQ_ABC_PWR_VR"
VOLTAGE"0"
BODY_TYPE"PLUMBING"
HDL_POWER"GND";
"A\NAC"1;
%"GND"
"1","(-7400,3375)","0","mstr_symbols","I10";
;
SIZE"1B"
BOM_COST"PROC_VRD_VCCIN_CPU0"
ROOM"VDDQ_ABC_PWR_VR"
VOLTAGE"0"
CDS_LIB"mstr_symbols"
BODY_TYPE"PLUMBING"
HDL_POWER"GND";
"A\NAC"2;
%"CAP"
"1","(-7400,3900)","0","mstr_discrete","I11";
;
CDS_LIB"mstr_discrete"
BOM_COST"MEM_VRD_PVDDQ_CD"
ROOM"VDDQ_KLM_PWR_VR"
CDS_LOCATION"C5G21"
$SEC"1"
CDS_SEC"1"
SIDE_SKU"1S"
LOCATION"C5G21"
VOLTAGE"4V"
TOLERANCE"20%"
PART_NUMBER"602433-112"
PACK_TYPE"0805"
VALUE"100UF"
MATERIAL"X5R";
"A"
$PN"1"3;
"B"
$PN"2"2;
%"CAP"
"1","(-7000,3900)","0","mstr_discrete","I15";
;
CDS_LIB"mstr_discrete"
BOM_COST"MEM_VRD_PVDDQ_CD"
ROOM"VDDQ_KLM_PWR_VR"
CDS_LOCATION"C5G22"
$SEC"1"
CDS_SEC"1"
SIDE_SKU"1S"
LOCATION"C5G22"
PART_NUMBER"602433-112"
PACK_TYPE"0805"
VALUE"100UF"
TOLERANCE"20%"
MATERIAL"X5R"
VOLTAGE"4V";
"A"
$PN"1"3;
"B"
$PN"2"2;
%"PVDDQ_ABC"
"1","(-7400,4325)","0","mstr_symbols","I26";
;
ROOM"VDDQ_ABC_PWR_VR"
BOM_COST"PROC_SOCKET "
VOLTAGE"1.2V"
CDS_LIB"mstr_symbols"
BODY_TYPE"PLUMBING"
HDL_POWER"PVDDQ_ABC";
"G\NAC"3;
%"GND"
"1","(-3150,1150)","0","mstr_symbols","I27";
;
CDS_LIB"mstr_symbols"
VOLTAGE"0"
ROOM"VDDQ_ABC_PWR_VR"
BOM_COST"PROC_VRD_VCCIN_CPU0"
SIZE"1B"
BODY_TYPE"PLUMBING"
HDL_POWER"GND";
"A\NAC"4;
%"PVDDQ_DEF"
"1","(-3150,1975)","0","mstr_symbols","I29";
;
CDS_LIB"mstr_symbols"
ROOM"VDDQ_DEF_PWR_VR"
BOM_COST"PROC_SOCKET "
VOLTAGE"1.2V"
BODY_TYPE"PLUMBING"
HDL_POWER"PVDDQ_DEF";
"G\NAC"5;
%"PVDDQ_ABC"
"1","(-7400,1925)","0","mstr_symbols","I3";
;
CDS_LIB"mstr_symbols"
ROOM"VDDQ_ABC_PWR_VR"
BOM_COST"PROC_SOCKET "
VOLTAGE"1.2V"
BODY_TYPE"PLUMBING"
HDL_POWER"PVDDQ_ABC";
"G\NAC"6;
%"GND"
"1","(-3150,2350)","0","mstr_symbols","I33";
;
VOLTAGE"0"
ROOM"VDDQ_ABC_PWR_VR"
BOM_COST"PROC_VRD_VCCIN_CPU0"
SIZE"1B"
CDS_LIB"mstr_symbols"
BODY_TYPE"PLUMBING"
HDL_POWER"GND";
"A\NAC"7;
%"PVDDQ_DEF"
"1","(-3150,3175)","0","mstr_symbols","I35";
;
ROOM"VDDQ_DEF_PWR_VR"
BOM_COST"PROC_SOCKET "
VOLTAGE"1.2V"
CDS_LIB"mstr_symbols"
BODY_TYPE"PLUMBING"
HDL_POWER"PVDDQ_DEF";
"G\NAC"8;
%"GND"
"1","(-3150,3400)","0","mstr_symbols","I36";
;
VOLTAGE"0"
ROOM"VDDQ_ABC_PWR_VR"
BOM_COST"PROC_VRD_VCCIN_CPU0"
SIZE"1B"
CDS_LIB"mstr_symbols"
BODY_TYPE"PLUMBING"
HDL_POWER"GND";
"A\NAC"9;
%"CAP"
"1","(-3150,3925)","0","mstr_discrete","I37";
;
CDS_LIB"mstr_discrete"
BOM_COST"MEM_VRD_PVDDQ_CD"
ROOM"VDDQ_KLM_PWR_VR"
CDS_LOCATION"C5G77"
$SEC"1"
CDS_SEC"1"
SIDE_SKU"1S"
VOLTAGE"4V"
VALUE"100UF"
LOCATION"C5G77"
PART_NUMBER"602433-112"
PACK_TYPE"0805"
MATERIAL"X5R"
TOLERANCE"20%";
"A"
$PN"1"10;
"B"
$PN"2"9;
%"CAP"
"1","(-2750,3925)","0","mstr_discrete","I41";
;
ROOM"VDDQ_KLM_PWR_VR"
BOM_COST"MEM_VRD_PVDDQ_CD"
CDS_LIB"mstr_discrete"
CDS_LOCATION"C5G78"
$SEC"1"
CDS_SEC"1"
SIDE_SKU"1S"
PART_NUMBER"602433-112"
PACK_TYPE"0805"
MATERIAL"X5R"
VOLTAGE"4V"
TOLERANCE"20%"
VALUE"100UF"
LOCATION"C5G78";
"A"
$PN"1"10;
"B"
$PN"2"9;
%"PVDDQ_DEF"
"1","(-3150,4350)","0","mstr_symbols","I50";
;
ROOM"VDDQ_DEF_PWR_VR"
BOM_COST"PROC_SOCKET "
VOLTAGE"1.2V"
CDS_LIB"mstr_symbols"
BODY_TYPE"PLUMBING"
HDL_POWER"PVDDQ_DEF";
"G\NAC"10;
%"CAP_A"
"1","(-7400,2775)","0","dev_discrete","I53";
;
CDS_SEC"1"
$SEC"1"
CDS_LOCATION"C5G41"
CDS_LIB"dev_discrete"
ROOM"PVDDQ_KLM"
SIDE_SKU"1S"
LOCATION"C5G41"
VALUE"22.0UF"
PART_NUMBER"E15431-004"
VOLTAGE"4V"
MATERIAL"X6S"
PACK_TYPE"0603V"
TOLERANCE"20%";
"B"
$PN"2"11;
"A"
$PN"1"12;
%"CAP_A"
"1","(-7100,2775)","0","dev_discrete","I54";
;
CDS_SEC"1"
$SEC"1"
CDS_LOCATION"C5G42"
CDS_LIB"dev_discrete"
ROOM"PVDDQ_KLM"
SIDE_SKU"1S"
PART_NUMBER"E15431-004"
TOLERANCE"20%"
VOLTAGE"4V"
MATERIAL"X6S"
PACK_TYPE"0603V"
LOCATION"C5G42"
VALUE"22.0UF";
"B"
$PN"2"11;
"A"
$PN"1"12;
%"CAP_A"
"1","(-6450,2775)","0","dev_discrete","I55";
;
CDS_SEC"1"
$SEC"1"
CDS_LOCATION"C5G44"
CDS_LIB"dev_discrete"
ROOM"PVDDQ_KLM"
SIDE_SKU"1S"
PACK_TYPE"0603V"
MATERIAL"X6S"
VOLTAGE"4V"
PART_NUMBER"E15431-004"
VALUE"22.0UF"
TOLERANCE"20%"
LOCATION"C5G44";
"B"
$PN"2"11;
"A"
$PN"1"12;
%"CAP_A"
"1","(-6800,2775)","0","dev_discrete","I56";
;
CDS_SEC"1"
$SEC"1"
CDS_LOCATION"C5G43"
CDS_LIB"dev_discrete"
ROOM"PVDDQ_KLM"
SIDE_SKU"1S"
PART_NUMBER"E15431-004"
VOLTAGE"4V"
PACK_TYPE"0603V"
LOCATION"C5G43"
VALUE"22.0UF"
TOLERANCE"20%"
MATERIAL"X6S";
"B"
$PN"2"11;
"A"
$PN"1"12;
%"CAP_A"
"1","(-5250,2775)","0","dev_discrete","I57";
;
CDS_SEC"1"
$SEC"1"
CDS_LOCATION"C5G48"
CDS_LIB"dev_discrete"
ROOM"PVDDQ_KLM"
SIDE_SKU"1S"
VALUE"22.0UF"
PART_NUMBER"E15431-004"
TOLERANCE"20%"
VOLTAGE"4V"
MATERIAL"X6S"
PACK_TYPE"0603V"
LOCATION"C5G48";
"B"
$PN"2"11;
"A"
$PN"1"12;
%"CAP_A"
"1","(-5550,2775)","0","dev_discrete","I58";
;
CDS_SEC"1"
$SEC"1"
CDS_LOCATION"C5G47"
CDS_LIB"dev_discrete"
ROOM"PVDDQ_KLM"
SIDE_SKU"1S"
LOCATION"C5G47"
VALUE"22.0UF"
VOLTAGE"4V"
TOLERANCE"20%"
PART_NUMBER"E15431-004"
PACK_TYPE"0603V"
MATERIAL"X6S";
"B"
$PN"2"11;
"A"
$PN"1"12;
%"CAP_A"
"1","(-5850,2775)","0","dev_discrete","I59";
;
CDS_SEC"1"
$SEC"1"
CDS_LOCATION"C5G46"
CDS_LIB"dev_discrete"
ROOM"PVDDQ_KLM"
SIDE_SKU"1S"
PACK_TYPE"0603V"
PART_NUMBER"E15431-004"
MATERIAL"X6S"
TOLERANCE"20%"
VOLTAGE"4V"
VALUE"22.0UF"
LOCATION"C5G46";
"B"
$PN"2"11;
"A"
$PN"1"12;
%"CAP_A"
"1","(-6150,2775)","0","dev_discrete","I60";
;
CDS_SEC"1"
$SEC"1"
CDS_LOCATION"C5G45"
CDS_LIB"dev_discrete"
ROOM"PVDDQ_KLM"
SIDE_SKU"1S"
PART_NUMBER"E15431-004"
VOLTAGE"4V"
MATERIAL"X6S"
PACK_TYPE"0603V"
TOLERANCE"20%"
VALUE"22.0UF"
LOCATION"C5G45";
"B"
$PN"2"11;
"A"
$PN"1"12;
%"CAP_A"
"1","(-4950,2775)","0","dev_discrete","I61";
;
CDS_SEC"1"
$SEC"1"
CDS_LOCATION"C5G49"
CDS_LIB"dev_discrete"
ROOM"PVDDQ_KLM"
SIDE_SKU"1S"
VALUE"22.0UF"
PART_NUMBER"E15431-004"
TOLERANCE"20%"
VOLTAGE"4V"
MATERIAL"X6S"
PACK_TYPE"0603V"
LOCATION"C5G49";
"B"
$PN"2"11;
"A"
$PN"1"12;
%"CAP_A"
"1","(-6150,1600)","0","dev_discrete","I62";
;
CDS_SEC"1"
$SEC"1"
CDS_LOCATION"C5G54"
CDS_LIB"dev_discrete"
ROOM"PVDDQ_KLM"
SIDE_SKU"1S"
VOLTAGE"4V"
LOCATION"C5G54"
MATERIAL"X6S"
VALUE"22.0UF"
TOLERANCE"20%"
PART_NUMBER"E15431-004"
PACK_TYPE"0603V";
"B"
$PN"2"1;
"A"
$PN"1"6;
%"CAP_A"
"1","(-4950,1600)","0","dev_discrete","I63";
;
CDS_SEC"1"
$SEC"1"
CDS_LOCATION"C5G58"
CDS_LIB"dev_discrete"
ROOM"PVDDQ_KLM"
SIDE_SKU"1S"
LOCATION"C5G58"
VALUE"22.0UF"
PART_NUMBER"E15431-004"
TOLERANCE"20%"
VOLTAGE"4V"
MATERIAL"X6S"
PACK_TYPE"0603V";
"B"
$PN"2"1;
"A"
$PN"1"6;
%"CAP_A"
"1","(-5250,1600)","0","dev_discrete","I64";
;
CDS_SEC"1"
$SEC"1"
CDS_LOCATION"C5G57"
CDS_LIB"dev_discrete"
ROOM"PVDDQ_KLM"
SIDE_SKU"1S"
LOCATION"C5G57"
VALUE"22.0UF"
PART_NUMBER"E15431-004"
TOLERANCE"20%"
VOLTAGE"4V"
MATERIAL"X6S"
PACK_TYPE"0603V";
"B"
$PN"2"1;
"A"
$PN"1"6;
%"CAP_A"
"1","(-5550,1600)","0","dev_discrete","I65";
;
CDS_SEC"1"
$SEC"1"
CDS_LOCATION"C5G56"
CDS_LIB"dev_discrete"
ROOM"PVDDQ_KLM"
SIDE_SKU"1S"
LOCATION"C5G56"
PART_NUMBER"E15431-004"
TOLERANCE"20%"
VOLTAGE"4V"
MATERIAL"X6S"
PACK_TYPE"0603V"
VALUE"22.0UF";
"B"
$PN"2"1;
"A"
$PN"1"6;
%"CAP_A"
"1","(-5850,1600)","0","dev_discrete","I66";
;
CDS_SEC"1"
$SEC"1"
CDS_LOCATION"C5G55"
CDS_LIB"dev_discrete"
ROOM"PVDDQ_KLM"
SIDE_SKU"1S"
VALUE"22.0UF"
PART_NUMBER"E15431-004"
LOCATION"C5G55"
TOLERANCE"20%"
VOLTAGE"4V"
MATERIAL"X6S"
PACK_TYPE"0603V";
"B"
$PN"2"1;
"A"
$PN"1"6;
%"CAP_A"
"1","(-6450,1600)","0","dev_discrete","I67";
;
CDS_SEC"1"
$SEC"1"
CDS_LOCATION"C5G53"
CDS_LIB"dev_discrete"
ROOM"PVDDQ_KLM"
SIDE_SKU"1S"
LOCATION"C5G53"
VALUE"22.0UF"
PART_NUMBER"E15431-004"
MATERIAL"X6S"
VOLTAGE"4V"
PACK_TYPE"0603V"
TOLERANCE"20%";
"B"
$PN"2"1;
"A"
$PN"1"6;
%"CAP_A"
"1","(-6800,1600)","0","dev_discrete","I68";
;
CDS_SEC"1"
$SEC"1"
CDS_LOCATION"C5G52"
CDS_LIB"dev_discrete"
ROOM"PVDDQ_KLM"
SIDE_SKU"1S"
VALUE"22.0UF"
TOLERANCE"20%"
PART_NUMBER"E15431-004"
LOCATION"C5G52"
VOLTAGE"4V"
MATERIAL"X6S"
PACK_TYPE"0603V";
"B"
$PN"2"1;
"A"
$PN"1"6;
%"CAP_A"
"1","(-7100,1600)","0","dev_discrete","I69";
;
CDS_SEC"1"
$SEC"1"
CDS_LOCATION"C5G51"
CDS_LIB"dev_discrete"
ROOM"PVDDQ_KLM"
SIDE_SKU"1S"
VALUE"22.0UF"
VOLTAGE"4V"
TOLERANCE"20%"
PART_NUMBER"E15431-004"
PACK_TYPE"0603V"
MATERIAL"X6S"
LOCATION"C5G51";
"B"
$PN"2"1;
"A"
$PN"1"6;
%"GND"
"1","(-7400,2275)","0","mstr_symbols","I7";
;
VOLTAGE"0"
ROOM"VDDQ_ABC_PWR_VR"
BOM_COST"PROC_VRD_VCCIN_CPU0"
SIZE"1B"
CDS_LIB"mstr_symbols"
BODY_TYPE"PLUMBING"
HDL_POWER"GND";
"A\NAC"11;
%"CAP_A"
"1","(-7400,1600)","0","dev_discrete","I70";
;
CDS_SEC"1"
$SEC"1"
CDS_LOCATION"C5G50"
CDS_LIB"dev_discrete"
ROOM"PVDDQ_KLM"
SIDE_SKU"1S"
PART_NUMBER"E15431-004"
VOLTAGE"4V"
VALUE"22.0UF"
TOLERANCE"20%"
MATERIAL"X6S"
PACK_TYPE"0603V"
LOCATION"C5G50";
"B"
$PN"2"1;
"A"
$PN"1"6;
%"CAP_A"
"1","(-700,2850)","0","dev_discrete","I71";
;
CDS_SEC"1"
$SEC"1"
CDS_LOCATION"C5G67"
ROOM"PVDDQ_KLM"
CDS_LIB"dev_discrete"
SIDE_SKU"1S"
LOCATION"C5G67"
VALUE"22.0UF"
PART_NUMBER"E15431-004"
TOLERANCE"20%"
VOLTAGE"4V"
MATERIAL"X6S"
PACK_TYPE"0603V";
"B"
$PN"2"7;
"A"
$PN"1"8;
%"CAP_A"
"1","(-1000,2850)","0","dev_discrete","I72";
;
CDS_SEC"1"
$SEC"1"
CDS_LOCATION"C5G66"
ROOM"PVDDQ_KLM"
CDS_LIB"dev_discrete"
SIDE_SKU"1S"
LOCATION"C5G66"
VALUE"22.0UF"
PART_NUMBER"E15431-004"
TOLERANCE"20%"
VOLTAGE"4V"
MATERIAL"X6S"
PACK_TYPE"0603V";
"B"
$PN"2"7;
"A"
$PN"1"8;
%"CAP_A"
"1","(-1300,2850)","0","dev_discrete","I73";
;
CDS_SEC"1"
$SEC"1"
CDS_LOCATION"C5G65"
ROOM"PVDDQ_KLM"
CDS_LIB"dev_discrete"
SIDE_SKU"1S"
LOCATION"C5G65"
PART_NUMBER"E15431-004"
TOLERANCE"20%"
VOLTAGE"4V"
MATERIAL"X6S"
PACK_TYPE"0603V"
VALUE"22.0UF";
"B"
$PN"2"7;
"A"
$PN"1"8;
%"CAP_A"
"1","(-1600,2850)","0","dev_discrete","I74";
;
CDS_SEC"1"
$SEC"1"
CDS_LOCATION"C5G64"
ROOM"PVDDQ_KLM"
CDS_LIB"dev_discrete"
SIDE_SKU"1S"
LOCATION"C5G64"
VALUE"22.0UF"
PART_NUMBER"E15431-004"
TOLERANCE"20%"
VOLTAGE"4V"
MATERIAL"X6S"
PACK_TYPE"0603V";
"B"
$PN"2"7;
"A"
$PN"1"8;
%"CAP_A"
"1","(-1900,2850)","0","dev_discrete","I75";
;
CDS_SEC"1"
$SEC"1"
CDS_LOCATION"C5G63"
ROOM"PVDDQ_KLM"
CDS_LIB"dev_discrete"
SIDE_SKU"1S"
LOCATION"C5G63"
VALUE"22.0UF"
PART_NUMBER"E15431-004"
TOLERANCE"20%"
VOLTAGE"4V"
MATERIAL"X6S"
PACK_TYPE"0603V";
"B"
$PN"2"7;
"A"
$PN"1"8;
%"CAP_A"
"1","(-2200,2850)","0","dev_discrete","I76";
;
CDS_SEC"1"
$SEC"1"
CDS_LOCATION"C5G62"
ROOM"PVDDQ_KLM"
CDS_LIB"dev_discrete"
SIDE_SKU"1S"
LOCATION"C5G62"
PACK_TYPE"0603V"
MATERIAL"X6S"
VOLTAGE"4V"
TOLERANCE"20%"
PART_NUMBER"E15431-004"
VALUE"22.0UF";
"B"
$PN"2"7;
"A"
$PN"1"8;
%"CAP_A"
"1","(-2550,2850)","0","dev_discrete","I77";
;
CDS_SEC"1"
$SEC"1"
CDS_LOCATION"C5G61"
ROOM"PVDDQ_KLM"
CDS_LIB"dev_discrete"
SIDE_SKU"1S"
LOCATION"C5G61"
VALUE"22.0UF"
PART_NUMBER"E15431-004"
TOLERANCE"20%"
VOLTAGE"4V"
MATERIAL"X6S"
PACK_TYPE"0603V";
"B"
$PN"2"7;
"A"
$PN"1"8;
%"CAP_A"
"1","(-2850,2850)","0","dev_discrete","I78";
;
CDS_SEC"1"
$SEC"1"
CDS_LOCATION"C5G60"
ROOM"PVDDQ_KLM"
CDS_LIB"dev_discrete"
SIDE_SKU"1S"
PACK_TYPE"0603V"
LOCATION"C5G60"
PART_NUMBER"E15431-004"
TOLERANCE"20%"
VOLTAGE"4V"
MATERIAL"X6S"
VALUE"22.0UF";
"B"
$PN"2"7;
"A"
$PN"1"8;
%"CAP_A"
"1","(-3150,2850)","0","dev_discrete","I79";
;
CDS_SEC"1"
$SEC"1"
CDS_LOCATION"C5G59"
ROOM"PVDDQ_KLM"
CDS_LIB"dev_discrete"
SIDE_SKU"1S"
LOCATION"C5G59"
VALUE"22.0UF"
PART_NUMBER"E15431-004"
TOLERANCE"20%"
VOLTAGE"4V"
MATERIAL"X6S"
PACK_TYPE"0603V";
"B"
$PN"2"7;
"A"
$PN"1"8;
%"CAP_A"
"1","(-700,1650)","0","dev_discrete","I80";
;
CDS_SEC"1"
$SEC"1"
CDS_LOCATION"C5G76"
CDS_LIB"dev_discrete"
ROOM"PVDDQ_KLM"
SIDE_SKU"1S"
LOCATION"C5G76"
PACK_TYPE"0603V"
MATERIAL"X6S"
VOLTAGE"4V"
TOLERANCE"20%"
PART_NUMBER"E15431-004"
VALUE"22.0UF";
"B"
$PN"2"4;
"A"
$PN"1"5;
%"CAP_A"
"1","(-1000,1650)","0","dev_discrete","I81";
;
CDS_SEC"1"
$SEC"1"
CDS_LOCATION"C5G75"
CDS_LIB"dev_discrete"
ROOM"PVDDQ_KLM"
SIDE_SKU"1S"
LOCATION"C5G75"
PACK_TYPE"0603V"
MATERIAL"X6S"
VOLTAGE"4V"
TOLERANCE"20%"
PART_NUMBER"E15431-004"
VALUE"22.0UF";
"B"
$PN"2"4;
"A"
$PN"1"5;
%"CAP_A"
"1","(-1300,1650)","0","dev_discrete","I82";
;
CDS_SEC"1"
$SEC"1"
CDS_LOCATION"C5G74"
CDS_LIB"dev_discrete"
ROOM"PVDDQ_KLM"
SIDE_SKU"1S"
LOCATION"C5G74"
PACK_TYPE"0603V"
MATERIAL"X6S"
VOLTAGE"4V"
TOLERANCE"20%"
PART_NUMBER"E15431-004"
VALUE"22.0UF";
"B"
$PN"2"4;
"A"
$PN"1"5;
%"CAP_A"
"1","(-1600,1650)","0","dev_discrete","I83";
;
CDS_SEC"1"
$SEC"1"
CDS_LOCATION"C5G73"
CDS_LIB"dev_discrete"
ROOM"PVDDQ_KLM"
SIDE_SKU"1S"
LOCATION"C5G73"
PACK_TYPE"0603V"
MATERIAL"X6S"
VOLTAGE"4V"
TOLERANCE"20%"
PART_NUMBER"E15431-004"
VALUE"22.0UF";
"B"
$PN"2"4;
"A"
$PN"1"5;
%"CAP_A"
"1","(-1900,1650)","0","dev_discrete","I84";
;
CDS_SEC"1"
$SEC"1"
CDS_LOCATION"C5G72"
CDS_LIB"dev_discrete"
ROOM"PVDDQ_KLM"
SIDE_SKU"1S"
LOCATION"C5G72"
PACK_TYPE"0603V"
MATERIAL"X6S"
VOLTAGE"4V"
TOLERANCE"20%"
PART_NUMBER"E15431-004"
VALUE"22.0UF";
"B"
$PN"2"4;
"A"
$PN"1"5;
%"CAP_A"
"1","(-2200,1650)","0","dev_discrete","I85";
;
CDS_SEC"1"
$SEC"1"
CDS_LOCATION"C5G71"
CDS_LIB"dev_discrete"
ROOM"PVDDQ_KLM"
SIDE_SKU"1S"
LOCATION"C5G71"
VALUE"22.0UF"
PART_NUMBER"E15431-004"
TOLERANCE"20%"
VOLTAGE"4V"
MATERIAL"X6S"
PACK_TYPE"0603V";
"B"
$PN"2"4;
"A"
$PN"1"5;
%"CAP_A"
"1","(-2550,1650)","0","dev_discrete","I86";
;
CDS_SEC"1"
$SEC"1"
CDS_LOCATION"C5G70"
CDS_LIB"dev_discrete"
ROOM"PVDDQ_KLM"
SIDE_SKU"1S"
LOCATION"C5G70"
TOLERANCE"20%"
VOLTAGE"4V"
PACK_TYPE"0603V"
MATERIAL"X6S"
PART_NUMBER"E15431-004"
VALUE"22.0UF";
"B"
$PN"2"4;
"A"
$PN"1"5;
%"CAP_A"
"1","(-2850,1650)","0","dev_discrete","I87";
;
CDS_SEC"1"
$SEC"1"
CDS_LOCATION"C5G69"
CDS_LIB"dev_discrete"
ROOM"PVDDQ_KLM"
SIDE_SKU"1S"
LOCATION"C5G69"
PACK_TYPE"0603V"
PART_NUMBER"E15431-004"
MATERIAL"X6S"
VOLTAGE"4V"
TOLERANCE"20%"
VALUE"22.0UF";
"B"
$PN"2"4;
"A"
$PN"1"5;
%"CAP_A"
"1","(-3150,1650)","0","dev_discrete","I88";
;
CDS_SEC"1"
$SEC"1"
CDS_LOCATION"C5G68"
CDS_LIB"dev_discrete"
ROOM"PVDDQ_KLM"
SIDE_SKU"1S"
LOCATION"C5G68"
VOLTAGE"4V"
TOLERANCE"20%"
MATERIAL"X6S"
PACK_TYPE"0603V"
PART_NUMBER"E15431-004"
VALUE"22.0UF";
"B"
$PN"2"4;
"A"
$PN"1"5;
%"PVDDQ_ABC"
"1","(-7400,3100)","0","mstr_symbols","I9";
;
VOLTAGE"1.2V"
BOM_COST"PROC_SOCKET "
ROOM"VDDQ_ABC_PWR_VR"
CDS_LIB"mstr_symbols"
BODY_TYPE"PLUMBING"
HDL_POWER"PVDDQ_ABC";
"G\NAC"12;
END.
